(kicad_pcb
	(version 20260206)
	(generator "pcbnew")
	(generator_version "10.0")
	(general
		(thickness 1.6)
		(legacy_teardrops no)
	)
	(paper "A4")
	(title_block
		(title "01162023_DA0F0TEBIF0_F0T_Expander_BD_F_brd_V02_OCP.brd")
		(comment 1 "Grand Teton / footprints 5801-5809 of 9728")
	)
	(layers
		(0 "F.Cu" signal "TOP")
		(4 "In1.Cu" signal "GND")
		(6 "In2.Cu" signal "VCC")
		(8 "In3.Cu" signal "VCC1")
		(10 "In4.Cu" signal "GND1")
		(12 "In5.Cu" signal "IN1")
		(14 "In6.Cu" signal "GND2")
		(16 "In7.Cu" signal "IN2")
		(18 "In8.Cu" signal "GND3")
		(20 "In9.Cu" signal "IN3")
		(22 "In10.Cu" signal "GND4")
		(24 "In11.Cu" signal "IN4")
		(26 "In12.Cu" signal "GND5")
		(28 "In13.Cu" signal "IN5")
		(30 "In14.Cu" signal "GND6")
		(32 "In15.Cu" signal "IN6")
		(34 "In16.Cu" signal "GND7")
		(2 "B.Cu" signal "BOTTOM")
		(9 "F.Adhes" user "F.Adhesive")
		(11 "B.Adhes" user "B.Adhesive")
		(13 "F.Paste" user "Package Geometry/Pastemask Top")
		(15 "B.Paste" user "Package Geometry/Pastemask Bottom")
		(5 "F.SilkS" user "Ref Des/Silkscreen Top")
		(7 "B.SilkS" user "Ref Des/Silkscreen Bottom")
		(1 "F.Mask" user "Board Geometry/Soldermask Top")
		(3 "B.Mask" user "Board Geometry/Soldermask Bottom")
		(17 "Dwgs.User" user "User.Drawings")
		(19 "Cmts.User" user "User.Comments")
		(21 "Eco1.User" user "User.Eco1")
		(23 "Eco2.User" user "User.Eco2")
		(25 "Edge.Cuts" user "Board Geometry/Outline")
		(27 "Margin" user)
		(31 "F.CrtYd" user "Package Geometry/Place Bound Top")
		(29 "B.CrtYd" user "Package Geometry/Place Bound Bottom")
		(35 "F.Fab" user "Ref Des/Assembly Top")
		(33 "B.Fab" user "Ref Des/Assembly Bottom")
	)
	(footprint ""
		(layer "F.Cu")
		(at 184.837832 -350.098614 90)
		(property "Reference" "C381"
			(at 0 0 90)
			(layer "F.SilkS")
			(hide yes)
			(effects
				(font
					(size 1.27 1.27)
				)
			)
		)
		(property "Value" ""
			(at 0 0 90)
			(layer "F.Fab")
			(effects
				(font
					(size 1.27 1.27)
				)
			)
		)
		(duplicate_pad_numbers_are_jumpers no)
		(fp_line
			(start 0.299974 -0.150114)
			(end 0.299974 0.150114)
			(stroke
				(width 0.1)
				(type default)
			)
			(layer "F.Fab")
		)
		(fp_line
			(start -0.299974 -0.150114)
			(end 0.299974 -0.150114)
			(stroke
				(width 0.1)
				(type default)
			)
			(layer "F.Fab")
		)
		(fp_line
			(start 0.299974 0.150114)
			(end -0.299974 0.150114)
			(stroke
				(width 0.1)
				(type default)
			)
			(layer "F.Fab")
		)
		(fp_line
			(start -0.299974 0.150114)
			(end -0.299974 -0.150114)
			(stroke
				(width 0.1)
				(type default)
			)
			(layer "F.Fab")
		)
		(pad "1" smd rect
			(at -0.2667 0 90)
			(size 0.3048 0.381)
			(layers "F.Cu" "F.Mask" "F.Paste")
			(net "P5E_PEX1_STN7_TX_DN<123>")
		)
		(pad "2" smd rect
			(at 0.2667 0 90)
			(size 0.3048 0.381)
			(layers "F.Cu" "F.Mask" "F.Paste")
			(net "P5E_PEX1_STN7_TX_C_DN<123>")
		)
	)
	(footprint ""
		(layer "F.Cu")
		(at 23.330408 -350.098614 90)
		(property "Reference" "C2155"
			(at 0 0 90)
			(layer "F.SilkS")
			(hide yes)
			(effects
				(font
					(size 1.27 1.27)
				)
			)
		)
		(property "Value" ""
			(at 0 0 90)
			(layer "F.Fab")
			(effects
				(font
					(size 1.27 1.27)
				)
			)
		)
		(duplicate_pad_numbers_are_jumpers no)
		(fp_line
			(start 0.299974 -0.150114)
			(end 0.299974 0.150114)
			(stroke
				(width 0.1)
				(type default)
			)
			(layer "F.Fab")
		)
		(fp_line
			(start -0.299974 -0.150114)
			(end 0.299974 -0.150114)
			(stroke
				(width 0.1)
				(type default)
			)
			(layer "F.Fab")
		)
		(fp_line
			(start 0.299974 0.150114)
			(end -0.299974 0.150114)
			(stroke
				(width 0.1)
				(type default)
			)
			(layer "F.Fab")
		)
		(fp_line
			(start -0.299974 0.150114)
			(end -0.299974 -0.150114)
			(stroke
				(width 0.1)
				(type default)
			)
			(layer "F.Fab")
		)
		(pad "1" smd rect
			(at -0.2667 0 90)
			(size 0.3048 0.381)
			(layers "F.Cu" "F.Mask" "F.Paste")
			(net "P5E_PEX0_STN4_TX_DN<78>")
		)
		(pad "2" smd rect
			(at 0.2667 0 90)
			(size 0.3048 0.381)
			(layers "F.Cu" "F.Mask" "F.Paste")
			(net "P5E_PEX0_STN4_TX_C_DN<78>")
		)
	)
	(footprint ""
		(layer "F.Cu")
		(at 9.62914 -315.26607 180)
		(property "Reference" "PC1007"
			(at 0 0 180)
			(layer "F.SilkS")
			(hide yes)
			(effects
				(font
					(size 1.27 1.27)
				)
			)
		)
		(property "Value" ""
			(at 0 0 180)
			(layer "F.Fab")
			(effects
				(font
					(size 1.27 1.27)
				)
			)
		)
		(duplicate_pad_numbers_are_jumpers no)
		(fp_line
			(start 1.524 0.762)
			(end -1.524 0.762)
			(stroke
				(width 0.1524)
				(type default)
			)
			(layer "F.SilkS")
		)
		(fp_line
			(start 1.524 -0.762)
			(end 1.524 0.762)
			(stroke
				(width 0.1524)
				(type default)
			)
			(layer "F.SilkS")
		)
		(fp_line
			(start -1.524 0.762)
			(end -1.524 -0.762)
			(stroke
				(width 0.1524)
				(type default)
			)
			(layer "F.SilkS")
		)
		(fp_line
			(start -1.524 -0.762)
			(end 1.524 -0.762)
			(stroke
				(width 0.1524)
				(type default)
			)
			(layer "F.SilkS")
		)
		(fp_line
			(start 1.1049 0.724916)
			(end 1.1049 -0.724916)
			(stroke
				(width 0.1)
				(type default)
			)
			(layer "F.Fab")
		)
		(fp_line
			(start 1.1049 -0.724916)
			(end -1.1049 -0.724916)
			(stroke
				(width 0.1)
				(type default)
			)
			(layer "F.Fab")
		)
		(fp_line
			(start -1.1049 0.724916)
			(end 1.1049 0.724916)
			(stroke
				(width 0.1)
				(type default)
			)
			(layer "F.Fab")
		)
		(fp_line
			(start -1.1049 -0.724916)
			(end -1.1049 0.724916)
			(stroke
				(width 0.1)
				(type default)
			)
			(layer "F.Fab")
		)
		(pad "1" smd rect
			(at -0.889 0)
			(size 1.016 1.27)
			(layers "F.Cu" "F.Mask" "F.Paste")
			(net "SW_P12V_P1V25_PEX0_FLT")
		)
		(pad "2" smd rect
			(at 0.889 0)
			(size 1.016 1.27)
			(layers "F.Cu" "F.Mask" "F.Paste")
			(net "GND")
		)
	)
	(footprint ""
		(layer "F.Cu")
		(at 174.80915 -26.03373)
		(property "Reference" "R4064"
			(at 0 0 0)
			(layer "F.SilkS")
			(hide yes)
			(effects
				(font
					(size 1.27 1.27)
				)
			)
		)
		(property "Value" ""
			(at 0 0 0)
			(layer "F.Fab")
			(effects
				(font
					(size 1.27 1.27)
				)
			)
		)
		(duplicate_pad_numbers_are_jumpers no)
		(fp_line
			(start -0.7874 -0.4064)
			(end 0.7874 -0.4064)
			(stroke
				(width 0.1524)
				(type default)
			)
			(layer "F.SilkS")
		)
		(fp_line
			(start -0.7874 0.4064)
			(end -0.7874 -0.4064)
			(stroke
				(width 0.1524)
				(type default)
			)
			(layer "F.SilkS")
		)
		(fp_line
			(start 0.7874 -0.4064)
			(end 0.7874 0.4064)
			(stroke
				(width 0.1524)
				(type default)
			)
			(layer "F.SilkS")
		)
		(fp_line
			(start 0.7874 0.4064)
			(end -0.7874 0.4064)
			(stroke
				(width 0.1524)
				(type default)
			)
			(layer "F.SilkS")
		)
		(fp_line
			(start -0.67945 -0.305054)
			(end -0.12065 -0.305054)
			(stroke
				(width 0.1)
				(type default)
			)
			(layer "F.Fab")
		)
		(fp_line
			(start -0.67945 0.3048)
			(end -0.67945 -0.305054)
			(stroke
				(width 0.1)
				(type default)
			)
			(layer "F.Fab")
		)
		(fp_line
			(start -0.12065 -0.305054)
			(end -0.12065 -0.2794)
			(stroke
				(width 0.1)
				(type default)
			)
			(layer "F.Fab")
		)
		(fp_line
			(start -0.12065 -0.2794)
			(end 0.12065 -0.2794)
			(stroke
				(width 0.1)
				(type default)
			)
			(layer "F.Fab")
		)
		(fp_line
			(start -0.12065 0.2794)
			(end -0.12065 0.3048)
			(stroke
				(width 0.1)
				(type default)
			)
			(layer "F.Fab")
		)
		(fp_line
			(start -0.12065 0.3048)
			(end -0.67945 0.3048)
			(stroke
				(width 0.1)
				(type default)
			)
			(layer "F.Fab")
		)
		(fp_line
			(start 0.120396 0.2794)
			(end -0.12065 0.2794)
			(stroke
				(width 0.1)
				(type default)
			)
			(layer "F.Fab")
		)
		(fp_line
			(start 0.120396 0.3048)
			(end 0.120396 0.2794)
			(stroke
				(width 0.1)
				(type default)
			)
			(layer "F.Fab")
		)
		(fp_line
			(start 0.12065 -0.3048)
			(end 0.67945 -0.3048)
			(stroke
				(width 0.1)
				(type default)
			)
			(layer "F.Fab")
		)
		(fp_line
			(start 0.12065 -0.2794)
			(end 0.12065 -0.3048)
			(stroke
				(width 0.1)
				(type default)
			)
			(layer "F.Fab")
		)
		(fp_line
			(start 0.67945 -0.3048)
			(end 0.67945 0.3048)
			(stroke
				(width 0.1)
				(type default)
			)
			(layer "F.Fab")
		)
		(fp_line
			(start 0.67945 0.3048)
			(end 0.120396 0.3048)
			(stroke
				(width 0.1)
				(type default)
			)
			(layer "F.Fab")
		)
		(pad "1" smd circle
			(at -0.40005 0)
			(size 0 0)
			(layers "F.Cu" "F.Mask" "F.Paste")
			(net "P3V3_AUX")
		)
		(pad "2" smd circle
			(at 0.40005 0)
			(size 0 0)
			(layers "F.Cu" "F.Mask" "F.Paste")
			(net "PRSNT_SSD6_R_N")
		)
	)
	(footprint ""
		(layer "F.Cu")
		(at 234.460288 -97.258378 90)
		(property "Reference" "R5439"
			(at 0 0 90)
			(layer "F.SilkS")
			(hide yes)
			(effects
				(font
					(size 1.27 1.27)
				)
			)
		)
		(property "Value" ""
			(at 0 0 90)
			(layer "F.Fab")
			(effects
				(font
					(size 1.27 1.27)
				)
			)
		)
		(duplicate_pad_numbers_are_jumpers no)
		(fp_line
			(start 0.7874 -0.4064)
			(end 0.7874 0.4064)
			(stroke
				(width 0.1524)
				(type default)
			)
			(layer "F.SilkS")
		)
		(fp_line
			(start -0.7874 -0.4064)
			(end 0.7874 -0.4064)
			(stroke
				(width 0.1524)
				(type default)
			)
			(layer "F.SilkS")
		)
		(fp_line
			(start 0.7874 0.4064)
			(end -0.7874 0.4064)
			(stroke
				(width 0.1524)
				(type default)
			)
			(layer "F.SilkS")
		)
		(fp_line
			(start -0.7874 0.4064)
			(end -0.7874 -0.4064)
			(stroke
				(width 0.1524)
				(type default)
			)
			(layer "F.SilkS")
		)
		(fp_line
			(start -0.12065 -0.305054)
			(end -0.12065 -0.2794)
			(stroke
				(width 0.1)
				(type default)
			)
			(layer "F.Fab")
		)
		(fp_line
			(start -0.67945 -0.305054)
			(end -0.12065 -0.305054)
			(stroke
				(width 0.1)
				(type default)
			)
			(layer "F.Fab")
		)
		(fp_line
			(start 0.67945 -0.3048)
			(end 0.67945 0.3048)
			(stroke
				(width 0.1)
				(type default)
			)
			(layer "F.Fab")
		)
		(fp_line
			(start 0.12065 -0.3048)
			(end 0.67945 -0.3048)
			(stroke
				(width 0.1)
				(type default)
			)
			(layer "F.Fab")
		)
		(fp_line
			(start 0.12065 -0.2794)
			(end 0.12065 -0.3048)
			(stroke
				(width 0.1)
				(type default)
			)
			(layer "F.Fab")
		)
		(fp_line
			(start -0.12065 -0.2794)
			(end 0.12065 -0.2794)
			(stroke
				(width 0.1)
				(type default)
			)
			(layer "F.Fab")
		)
		(fp_line
			(start 0.120396 0.2794)
			(end -0.12065 0.2794)
			(stroke
				(width 0.1)
				(type default)
			)
			(layer "F.Fab")
		)
		(fp_line
			(start -0.12065 0.2794)
			(end -0.12065 0.3048)
			(stroke
				(width 0.1)
				(type default)
			)
			(layer "F.Fab")
		)
		(fp_line
			(start 0.67945 0.3048)
			(end 0.120396 0.3048)
			(stroke
				(width 0.1)
				(type default)
			)
			(layer "F.Fab")
		)
		(fp_line
			(start 0.120396 0.3048)
			(end 0.120396 0.2794)
			(stroke
				(width 0.1)
				(type default)
			)
			(layer "F.Fab")
		)
		(fp_line
			(start -0.12065 0.3048)
			(end -0.67945 0.3048)
			(stroke
				(width 0.1)
				(type default)
			)
			(layer "F.Fab")
		)
		(fp_line
			(start -0.67945 0.3048)
			(end -0.67945 -0.305054)
			(stroke
				(width 0.1)
				(type default)
			)
			(layer "F.Fab")
		)
		(pad "1" smd circle
			(at -0.40005 0 90)
			(size 0 0)
			(layers "F.Cu" "F.Mask" "F.Paste")
			(net "RST_PEX_USB_HUB_R_N")
		)
		(pad "2" smd circle
			(at 0.40005 0 90)
			(size 0 0)
			(layers "F.Cu" "F.Mask" "F.Paste")
			(net "GND")
		)
	)
	(footprint ""
		(layer "F.Cu")
		(at 293.49319 -213.523068 -90)
		(property "Reference" "R3397"
			(at 0 0 270)
			(layer "F.SilkS")
			(hide yes)
			(effects
				(font
					(size 1.27 1.27)
				)
			)
		)
		(property "Value" ""
			(at 0 0 270)
			(layer "F.Fab")
			(effects
				(font
					(size 1.27 1.27)
				)
			)
		)
		(duplicate_pad_numbers_are_jumpers no)
		(fp_line
			(start -0.7874 0.4064)
			(end -0.7874 -0.4064)
			(stroke
				(width 0.1524)
				(type default)
			)
			(layer "F.SilkS")
		)
		(fp_line
			(start 0.7874 0.4064)
			(end -0.7874 0.4064)
			(stroke
				(width 0.1524)
				(type default)
			)
			(layer "F.SilkS")
		)
		(fp_line
			(start -0.7874 -0.4064)
			(end 0.7874 -0.4064)
			(stroke
				(width 0.1524)
				(type default)
			)
			(layer "F.SilkS")
		)
		(fp_line
			(start 0.7874 -0.4064)
			(end 0.7874 0.4064)
			(stroke
				(width 0.1524)
				(type default)
			)
			(layer "F.SilkS")
		)
		(fp_line
			(start -0.67945 0.3048)
			(end -0.67945 -0.305054)
			(stroke
				(width 0.1)
				(type default)
			)
			(layer "F.Fab")
		)
		(fp_line
			(start -0.12065 0.3048)
			(end -0.67945 0.3048)
			(stroke
				(width 0.1)
				(type default)
			)
			(layer "F.Fab")
		)
		(fp_line
			(start 0.120396 0.3048)
			(end 0.120396 0.2794)
			(stroke
				(width 0.1)
				(type default)
			)
			(layer "F.Fab")
		)
		(fp_line
			(start 0.67945 0.3048)
			(end 0.120396 0.3048)
			(stroke
				(width 0.1)
				(type default)
			)
			(layer "F.Fab")
		)
		(fp_line
			(start -0.12065 0.2794)
			(end -0.12065 0.3048)
			(stroke
				(width 0.1)
				(type default)
			)
			(layer "F.Fab")
		)
		(fp_line
			(start 0.120396 0.2794)
			(end -0.12065 0.2794)
			(stroke
				(width 0.1)
				(type default)
			)
			(layer "F.Fab")
		)
		(fp_line
			(start -0.12065 -0.2794)
			(end 0.12065 -0.2794)
			(stroke
				(width 0.1)
				(type default)
			)
			(layer "F.Fab")
		)
		(fp_line
			(start 0.12065 -0.2794)
			(end 0.12065 -0.3048)
			(stroke
				(width 0.1)
				(type default)
			)
			(layer "F.Fab")
		)
		(fp_line
			(start 0.12065 -0.3048)
			(end 0.67945 -0.3048)
			(stroke
				(width 0.1)
				(type default)
			)
			(layer "F.Fab")
		)
		(fp_line
			(start 0.67945 -0.3048)
			(end 0.67945 0.3048)
			(stroke
				(width 0.1)
				(type default)
			)
			(layer "F.Fab")
		)
		(fp_line
			(start -0.67945 -0.305054)
			(end -0.12065 -0.305054)
			(stroke
				(width 0.1)
				(type default)
			)
			(layer "F.Fab")
		)
		(fp_line
			(start -0.12065 -0.305054)
			(end -0.12065 -0.2794)
			(stroke
				(width 0.1)
				(type default)
			)
			(layer "F.Fab")
		)
		(pad "1" smd circle
			(at -0.40005 0 270)
			(size 0 0)
			(layers "F.Cu" "F.Mask" "F.Paste")
			(net "SPI_BIC1_MISO_LS23_R1")
		)
		(pad "2" smd circle
			(at 0.40005 0 270)
			(size 0 0)
			(layers "F.Cu" "F.Mask" "F.Paste")
			(net "SPI_BIC1_MISO_LS23_R")
		)
	)
	(footprint ""
		(layer "F.Cu")
		(at 152.738328 -130.408934)
		(property "Reference" "C250"
			(at 0 0 0)
			(layer "F.SilkS")
			(hide yes)
			(effects
				(font
					(size 1.27 1.27)
				)
			)
		)
		(property "Value" ""
			(at 0 0 0)
			(layer "F.Fab")
			(effects
				(font
					(size 1.27 1.27)
				)
			)
		)
		(duplicate_pad_numbers_are_jumpers no)
		(fp_line
			(start -0.299974 -0.150114)
			(end 0.299974 -0.150114)
			(stroke
				(width 0.1)
				(type default)
			)
			(layer "F.Fab")
		)
		(fp_line
			(start -0.299974 0.150114)
			(end -0.299974 -0.150114)
			(stroke
				(width 0.1)
				(type default)
			)
			(layer "F.Fab")
		)
		(fp_line
			(start 0.299974 -0.150114)
			(end 0.299974 0.150114)
			(stroke
				(width 0.1)
				(type default)
			)
			(layer "F.Fab")
		)
		(fp_line
			(start 0.299974 0.150114)
			(end -0.299974 0.150114)
			(stroke
				(width 0.1)
				(type default)
			)
			(layer "F.Fab")
		)
		(pad "1" smd rect
			(at -0.2667 0)
			(size 0.3048 0.381)
			(layers "F.Cu" "F.Mask" "F.Paste")
			(net "P5E_PEX1_STN1_TX_DP<28>")
		)
		(pad "2" smd rect
			(at 0.2667 0)
			(size 0.3048 0.381)
			(layers "F.Cu" "F.Mask" "F.Paste")
			(net "P5E_PEX1_STN1_TX_C_DP<28>")
		)
	)
	(footprint ""
		(layer "F.Cu")
		(at 56.034686 -370.421662 180)
		(property "Reference" "C3986"
			(at 0 0 180)
			(layer "F.SilkS")
			(hide yes)
			(effects
				(font
					(size 1.27 1.27)
				)
			)
		)
		(property "Value" ""
			(at 0 0 180)
			(layer "F.Fab")
			(effects
				(font
					(size 1.27 1.27)
				)
			)
		)
		(duplicate_pad_numbers_are_jumpers no)
		(fp_line
			(start 0.299974 0.150114)
			(end -0.299974 0.150114)
			(stroke
				(width 0.1)
				(type default)
			)
			(layer "F.Fab")
		)
		(fp_line
			(start 0.299974 -0.150114)
			(end 0.299974 0.150114)
			(stroke
				(width 0.1)
				(type default)
			)
			(layer "F.Fab")
		)
		(fp_line
			(start -0.299974 0.150114)
			(end -0.299974 -0.150114)
			(stroke
				(width 0.1)
				(type default)
			)
			(layer "F.Fab")
		)
		(fp_line
			(start -0.299974 -0.150114)
			(end 0.299974 -0.150114)
			(stroke
				(width 0.1)
				(type default)
			)
			(layer "F.Fab")
		)
		(pad "1" smd rect
			(at -0.2667 0 180)
			(size 0.3048 0.381)
			(layers "F.Cu" "F.Mask" "F.Paste")
			(net "P4E_PEX0_STN3_TX_DP<48>")
		)
		(pad "2" smd rect
			(at 0.2667 0 180)
			(size 0.3048 0.381)
			(layers "F.Cu" "F.Mask" "F.Paste")
			(net "P4E_PEX0_STN3_TX_C_DP<48>")
		)
	)
	(footprint ""
		(layer "F.Cu")
		(at 362.291376 -280.44902 -90)
		(property "Reference" "PR161"
			(at 0 0 270)
			(layer "F.SilkS")
			(hide yes)
			(effects
				(font
					(size 1.27 1.27)
				)
			)
		)
		(property "Value" ""
			(at 0 0 270)
			(layer "F.Fab")
			(effects
				(font
					(size 1.27 1.27)
				)
			)
		)
		(duplicate_pad_numbers_are_jumpers no)
		(fp_line
			(start -0.7874 0.4064)
			(end -0.7874 -0.4064)
			(stroke
				(width 0.1524)
				(type default)
			)
			(layer "F.SilkS")
		)
		(fp_line
			(start 0.7874 0.4064)
			(end -0.7874 0.4064)
			(stroke
				(width 0.1524)
				(type default)
			)
			(layer "F.SilkS")
		)
		(fp_line
			(start -0.7874 -0.4064)
			(end 0.7874 -0.4064)
			(stroke
				(width 0.1524)
				(type default)
			)
			(layer "F.SilkS")
		)
		(fp_line
			(start 0.7874 -0.4064)
			(end 0.7874 0.4064)
			(stroke
				(width 0.1524)
				(type default)
			)
			(layer "F.SilkS")
		)
		(fp_line
			(start -0.67945 0.3048)
			(end -0.67945 -0.305054)
			(stroke
				(width 0.1)
				(type default)
			)
			(layer "F.Fab")
		)
		(fp_line
			(start -0.12065 0.3048)
			(end -0.67945 0.3048)
			(stroke
				(width 0.1)
				(type default)
			)
			(layer "F.Fab")
		)
		(fp_line
			(start 0.120396 0.3048)
			(end 0.120396 0.2794)
			(stroke
				(width 0.1)
				(type default)
			)
			(layer "F.Fab")
		)
		(fp_line
			(start 0.67945 0.3048)
			(end 0.120396 0.3048)
			(stroke
				(width 0.1)
				(type default)
			)
			(layer "F.Fab")
		)
		(fp_line
			(start -0.12065 0.2794)
			(end -0.12065 0.3048)
			(stroke
				(width 0.1)
				(type default)
			)
			(layer "F.Fab")
		)
		(fp_line
			(start 0.120396 0.2794)
			(end -0.12065 0.2794)
			(stroke
				(width 0.1)
				(type default)
			)
			(layer "F.Fab")
		)
		(fp_line
			(start -0.12065 -0.2794)
			(end 0.12065 -0.2794)
			(stroke
				(width 0.1)
				(type default)
			)
			(layer "F.Fab")
		)
		(fp_line
			(start 0.12065 -0.2794)
			(end 0.12065 -0.3048)
			(stroke
				(width 0.1)
				(type default)
			)
			(layer "F.Fab")
		)
		(fp_line
			(start 0.12065 -0.3048)
			(end 0.67945 -0.3048)
			(stroke
				(width 0.1)
				(type default)
			)
			(layer "F.Fab")
		)
		(fp_line
			(start 0.67945 -0.3048)
			(end 0.67945 0.3048)
			(stroke
				(width 0.1)
				(type default)
			)
			(layer "F.Fab")
		)
		(fp_line
			(start -0.67945 -0.305054)
			(end -0.12065 -0.305054)
			(stroke
				(width 0.1)
				(type default)
			)
			(layer "F.Fab")
		)
		(fp_line
			(start -0.12065 -0.305054)
			(end -0.12065 -0.2794)
			(stroke
				(width 0.1)
				(type default)
			)
			(layer "F.Fab")
		)
		(pad "1" smd circle
			(at -0.40005 0 270)
			(size 0 0)
			(layers "F.Cu" "F.Mask" "F.Paste")
			(net "SW_P0V8_PEX3_BOOT2")
		)
		(pad "2" smd circle
			(at 0.40005 0 270)
			(size 0 0)
			(layers "F.Cu" "F.Mask" "F.Paste")
			(net "SW_P0V8_PEX3_BOOT2_R")
		)
	)
)
